# S9S_MB_2U (Grand Teton) — schematic netlist excerpt (pin names and nets, part order shuffled) for the footprints in the layout excerpt that follows; sources: Cadence DE-HDL packaged netlist, KiCad conversion of 03242023_DA0F0TMBIJ0_F0T_Motherboard_J_brd_V01_OCP.brd

R54  Q_RES  10 1% CHIP  pkg 0402LF  page 47 : A = DBP_CPU1_HOOK9_MBP3_GTL_QS_R_N ; B = DBP_CPU_HOOK9_MBP3_GTL_QS_N
PC189  Q_CAPP  330UF 2.5V +10/-35% EMPTY  pkg SMLF  page 285 : A = PVCCIN_CPU1 ; B = GND

(kicad_pcb
	(version 20260206)
	(generator "pcbnew")
	(generator_version "10.0")
	(general
		(thickness 1.6)
		(legacy_teardrops no)
	)
	(paper "A4")
	(title_block
		(title "03242023_DA0F0TMBIJ0_F0T_Motherboard_J_brd_V01_OCP.brd")
		(comment 1 "Grand Teton / footprints 5140-5141 of 6105")
	)
	(layers
		(0 "F.Cu" signal "TOP")
		(4 "In1.Cu" signal "GND")
		(6 "In2.Cu" signal "IN1")
		(8 "In3.Cu" signal "GND1")
		(10 "In4.Cu" signal "IN2")
		(12 "In5.Cu" signal "GND2")
		(14 "In6.Cu" signal "IN3")
		(16 "In7.Cu" signal "GND3")
		(18 "In8.Cu" signal "VCC")
		(20 "In9.Cu" signal "VCC1")
		(22 "In10.Cu" signal "GND4")
		(24 "In11.Cu" signal "IN4")
		(26 "In12.Cu" signal "GND5")
		(28 "In13.Cu" signal "IN5")
		(30 "In14.Cu" signal "GND6")
		(32 "In15.Cu" signal "IN6")
		(34 "In16.Cu" signal "GND7")
		(2 "B.Cu" signal "BOTTOM")
		(9 "F.Adhes" user "F.Adhesive")
		(11 "B.Adhes" user "B.Adhesive")
		(13 "F.Paste" user "Package Geometry/Pastemask Top")
		(15 "B.Paste" user "Package Geometry/Pastemask Bottom")
		(5 "F.SilkS" user "Ref Des/Silkscreen Top")
		(7 "B.SilkS" user "Ref Des/Silkscreen Bottom")
		(1 "F.Mask" user "Board Geometry/Soldermask Top")
		(3 "B.Mask" user "Board Geometry/Soldermask Bottom")
		(17 "Dwgs.User" user "User.Drawings")
		(19 "Cmts.User" user "User.Comments")
		(21 "Eco1.User" user "User.Eco1")
		(23 "Eco2.User" user "User.Eco2")
		(25 "Edge.Cuts" user "Board Geometry/Outline")
		(27 "Margin" user)
		(31 "F.CrtYd" user "Package Geometry/Place Bound Top")
		(29 "B.CrtYd" user "Package Geometry/Place Bound Bottom")
		(35 "F.Fab" user "Ref Des/Assembly Top")
		(33 "B.Fab" user "Ref Des/Assembly Bottom")
	)
	(footprint ""
		(layer "B.Cu")
		(at 88.837262 -329.970384 -90)
		(property "Reference" "PC189"
			(at 0 0 90)
			(layer "B.SilkS")
			(hide yes)
			(effects
				(font
					(size 1.27 1.27)
				)
				(justify mirror)
			)
		)
		(property "Value" ""
			(at 0 0 90)
			(layer "B.Fab")
			(effects
				(font
					(size 1.27 1.27)
				)
				(justify mirror)
			)
		)
		(duplicate_pad_numbers_are_jumpers no)
		(fp_line
			(start -4.533392 2.249932)
			(end 4.533392 2.249932)
			(stroke
				(width 0.1524)
				(type default)
			)
			(layer "B.SilkS")
		)
		(fp_line
			(start 4.533392 2.249932)
			(end 4.533392 -2.249932)
			(stroke
				(width 0.1524)
				(type default)
			)
			(layer "B.SilkS")
		)
		(fp_line
			(start -4.533392 -2.249932)
			(end -4.533392 2.249932)
			(stroke
				(width 0.1524)
				(type default)
			)
			(layer "B.SilkS")
		)
		(fp_line
			(start 4.533392 -2.249932)
			(end -4.533392 -2.249932)
			(stroke
				(width 0.1524)
				(type default)
			)
			(layer "B.SilkS")
		)
		(fp_rect
			(start 5.39242 2.326132)
			(end 4.533392 -2.326132)
			(stroke
				(width 0)
				(type default)
			)
			(fill yes)
			(layer "B.SilkS")
		)
		(fp_line
			(start -3.750056 2.249932)
			(end 3.750056 2.249932)
			(stroke
				(width 0.1)
				(type default)
			)
			(layer "B.Fab")
		)
		(fp_line
			(start 3.750056 2.249932)
			(end 3.750056 -2.249932)
			(stroke
				(width 0.1)
				(type default)
			)
			(layer "B.Fab")
		)
		(fp_line
			(start -3.750056 -2.249932)
			(end -3.750056 2.249932)
			(stroke
				(width 0.1)
				(type default)
			)
			(layer "B.Fab")
		)
		(fp_line
			(start 3.750056 -2.249932)
			(end -3.750056 -2.249932)
			(stroke
				(width 0.1)
				(type default)
			)
			(layer "B.Fab")
		)
		(fp_text user "-"
			(at -4.634484 0.883412 270)
			(unlocked yes)
			(layer "B.SilkS")
			(effects
				(font
					(size 1.905 1.4224)
					(thickness 0.1524)
				)
				(justify left mirror)
			)
		)
		(fp_text user "+"
			(at 6.322314 0.786384 180)
			(unlocked yes)
			(layer "B.SilkS")
			(effects
				(font
					(size 1.905 1.4224)
					(thickness 0.1524)
				)
				(justify left mirror)
			)
		)
		(fp_text user "+"
			(at 6.322314 0.786384 180)
			(unlocked yes)
			(layer "B.Fab")
			(effects
				(font
					(size 1.905 1.4224)
					(thickness 0.1524)
				)
				(justify left mirror)
			)
		)
		(fp_text user "-"
			(at -4.8514 -0.14605 270)
			(unlocked yes)
			(layer "B.Fab")
			(effects
				(font
					(size 1.905 1.4224)
					(thickness 0.1524)
				)
				(justify left mirror)
			)
		)
		(pad "1" smd rect
			(at 3.199892 0 90)
			(size 2.413 2.8194)
			(layers "B.Cu" "B.Mask" "B.Paste")
			(net "PVCCIN_CPU1")
		)
		(pad "2" smd rect
			(at -3.199892 0 90)
			(size 2.413 2.8194)
			(layers "B.Cu" "B.Mask" "B.Paste")
			(net "GND")
		)
	)
	(footprint ""
		(layer "B.Cu")
		(at 70.369684 -185.791856 90)
		(property "Reference" "R54"
			(at 0 0 90)
			(layer "B.SilkS")
			(hide yes)
			(effects
				(font
					(size 1.27 1.27)
				)
				(justify mirror)
			)
		)
		(property "Value" ""
			(at 0 0 90)
			(layer "B.Fab")
			(effects
				(font
					(size 1.27 1.27)
				)
				(justify mirror)
			)
		)
		(duplicate_pad_numbers_are_jumpers no)
		(fp_line
			(start 0.7874 -0.4064)
			(end -0.7874 -0.4064)
			(stroke
				(width 0.1524)
				(type default)
			)
			(layer "B.SilkS")
		)
		(fp_line
			(start -0.7874 -0.4064)
			(end -0.7874 0.4064)
			(stroke
				(width 0.1524)
				(type default)
			)
			(layer "B.SilkS")
		)
		(fp_line
			(start 0.7874 0.4064)
			(end 0.7874 -0.4064)
			(stroke
				(width 0.1524)
				(type default)
			)
			(layer "B.SilkS")
		)
		(fp_line
			(start -0.7874 0.4064)
			(end 0.7874 0.4064)
			(stroke
				(width 0.1524)
				(type default)
			)
			(layer "B.SilkS")
		)
		(fp_line
			(start 0.67945 -0.305054)
			(end 0.12065 -0.305054)
			(stroke
				(width 0.1)
				(type default)
			)
			(layer "B.Fab")
		)
		(fp_line
			(start 0.12065 -0.305054)
			(end 0.12065 -0.2794)
			(stroke
				(width 0.1)
				(type default)
			)
			(layer "B.Fab")
		)
		(fp_line
			(start -0.12065 -0.3048)
			(end -0.67945 -0.3048)
			(stroke
				(width 0.1)
				(type default)
			)
			(layer "B.Fab")
		)
		(fp_line
			(start -0.67945 -0.3048)
			(end -0.67945 0.3048)
			(stroke
				(width 0.1)
				(type default)
			)
			(layer "B.Fab")
		)
		(fp_line
			(start 0.12065 -0.2794)
			(end -0.12065 -0.2794)
			(stroke
				(width 0.1)
				(type default)
			)
			(layer "B.Fab")
		)
		(fp_line
			(start -0.12065 -0.2794)
			(end -0.12065 -0.3048)
			(stroke
				(width 0.1)
				(type default)
			)
			(layer "B.Fab")
		)
		(fp_line
			(start 0.12065 0.2794)
			(end 0.12065 0.3048)
			(stroke
				(width 0.1)
				(type default)
			)
			(layer "B.Fab")
		)
		(fp_line
			(start -0.120396 0.2794)
			(end 0.12065 0.2794)
			(stroke
				(width 0.1)
				(type default)
			)
			(layer "B.Fab")
		)
		(fp_line
			(start 0.67945 0.3048)
			(end 0.67945 -0.305054)
			(stroke
				(width 0.1)
				(type default)
			)
			(layer "B.Fab")
		)
		(fp_line
			(start 0.12065 0.3048)
			(end 0.67945 0.3048)
			(stroke
				(width 0.1)
				(type default)
			)
			(layer "B.Fab")
		)
		(fp_line
			(start -0.120396 0.3048)
			(end -0.120396 0.2794)
			(stroke
				(width 0.1)
				(type default)
			)
			(layer "B.Fab")
		)
		(fp_line
			(start -0.67945 0.3048)
			(end -0.120396 0.3048)
			(stroke
				(width 0.1)
				(type default)
			)
			(layer "B.Fab")
		)
		(pad "1" smd circle
			(at 0.40005 0 270)
			(size 0 0)
			(layers "B.Cu" "B.Mask" "B.Paste")
			(net "DBP_CPU1_HOOK9_MBP3_GTL_QS_R_N")
		)
		(pad "2" smd circle
			(at -0.40005 0 270)
			(size 0 0)
			(layers "B.Cu" "B.Mask" "B.Paste")
			(net "DBP_CPU_HOOK9_MBP3_GTL_QS_N")
		)
	)
)
